FILE_TYPE = MULTI_PHYS_TABLE;

PART '74LVC2G07DW7'

{========================================================================================}
:VALUE           | PART_TYPE | MATERIAL | PART_NUMBER       = STANDARD    | LIFECYCLE      | PART_NUMBER       | JEDEC_TYPE             | DESCRIPTION                                | MANUFTR | MANUF_PN        | RD_CMPLS_LVL | CMPLS_LVL | FROM_PJ    | CLASS | DIP_SMD | DATA                    | EE_CHECK_LIST | FP_ECN           | PSL | CREATOR | STATUS | MSD | ESD_CDM | ESD_HBM | ESD_MM | PIN_LENGTH_SHORT_PIN | PIN_LENGTH_LONG_PIN | CREATEDAY  ;
{========================================================================================}
 '74LVC2G07DW-7' | 'SMLF'    | 'IC'     | 'AL002G07003'(!)  = ''          | ''             | 'AL002G07003'     |'SOT363_0-65_2X1-25XC'| 'IC OTHER(6P)74LVC2G07DW-7(SOT-363)'       | 'DDS'   | '74LVC2G07DW-7' | 'EP(V1)'     | 'EP(V1)'  | 'F0C-IVES' | 'IC'  | ''      | 'DDS_74LVC2G07DW-7.pdf' | ''            | ''               | ''  | ''      | ''     | ''  | ''      | ''      | ''     | '0 MILS'             | '0 MILS'            | '20210611'
 '74LVC2G07DW-7' | 'SMLF'    | 'EMPTY'  | 'AL002G07003'(!)  = ''          | ''             | 'AL002G07003'     |'SOT363_0-65_2X1-25XC'| 'IC OTHER(6P)74LVC2G07DW-7(SOT-363)'       | 'DDS'   | '74LVC2G07DW-7' | 'EP(V1)'     | 'EP(V1)'  | 'F0C-IVES' | 'IC'  | ''      | 'DDS_74LVC2G07DW-7.pdf' | ''            | ''               | ''  | ''      | ''     | ''  | ''      | ''      | ''     | '0 MILS'             | '0 MILS'            | '20210611'
 '74LVC2G07DW-7' | 'SMLF'    | 'IC'     | 'AL002G07003SEL1'(!) = ''               | ''               | 'AL002G07003SEL1' |'SOT363_0-65_2X1-25XC'| 'IC OTHER(6P)74LVC2G07DW-7(SOT-363)SELASN' | 'DDS'   | '74LVC2G07DW-7' | 'EP(V1)'     | 'EP(V1)'  | 'F0C-IVES' | 'IC'  | ''      | 'DDS_74LVC2G07DW-7.pdf' | ''            | 'SEL_15QPN.xlsx' | ''  | ''      | ''     | ''  | ''      | ''      | ''     | '0 MILS'             | '0 MILS'            | '20230719'
 '74LVC2G07DW-7' | 'SMLF'    | 'EMPTY'  | 'AL002G07003SEL1'(!) = ''               | ''               | 'AL002G07003SEL1' |'SOT363_0-65_2X1-25XC'| 'IC OTHER(6P)74LVC2G07DW-7(SOT-363)SELASN' | 'DDS'   | '74LVC2G07DW-7' | 'EP(V1)'     | 'EP(V1)'  | 'F0C-IVES' | 'IC'  | ''      | 'DDS_74LVC2G07DW-7.pdf' | ''            | 'SEL_15QPN.xlsx' | ''  | ''      | ''     | ''  | ''      | ''      | ''     | '0 MILS'             | '0 MILS'            | '20230719'

END_PART

END.

